# TIMECARD (Time Appliance Project (Time Card)) — schematic netlist excerpt (pin names and nets, part order shuffled) for the footprints in the layout excerpt that follows; sources: Cadence DE-HDL packaged netlist, KiCad conversion of R4006-B0001-02_R01.brd

R192  RESISTOR  4.7KOHM 1%  pkg SMC_0402R_H016  page 10 : \1\ = FLASH_CLK ; \2\ = SG
R230  RESISTOR  0OHM -  pkg SMC_0402R_H016  page 31 : \1\ = UNNAMED_515_CAPACITOR_I138_1 ; \2\ = FPGA_CFG_INIT_N

(kicad_pcb
	(version 20260206)
	(generator "pcbnew")
	(generator_version "10.0")
	(general
		(thickness 1.6)
		(legacy_teardrops no)
	)
	(paper "A4")
	(title_block
		(title "timecard-production-celestica-r4006 — R4006-B0001-02_R01.brd")
		(comment 1 "Time Appliance Project (Time Card) / footprints 911-912 of 1113")
	)
	(layers
		(0 "F.Cu" signal "TOP")
		(4 "In1.Cu" signal "L02_GND1")
		(6 "In2.Cu" signal "L03_SIG1")
		(8 "In3.Cu" signal "L04_GND2")
		(10 "In4.Cu" signal "L05_VCC1")
		(12 "In5.Cu" signal "L06_VCC2")
		(14 "In6.Cu" signal "L07_GND3")
		(16 "In7.Cu" signal "L08_SIG2")
		(18 "In8.Cu" signal "L09_GND4")
		(2 "B.Cu" signal "BOTTOM")
		(9 "F.Adhes" user "F.Adhesive")
		(11 "B.Adhes" user "B.Adhesive")
		(13 "F.Paste" user "Package Geometry/Pastemask Top")
		(15 "B.Paste" user "Package Geometry/Pastemask Bottom")
		(5 "F.SilkS" user "Ref Des/Silkscreen Top")
		(7 "B.SilkS" user "Ref Des/Silkscreen Bottom")
		(1 "F.Mask" user "Board Geometry/Soldermask Top")
		(3 "B.Mask" user "Board Geometry/Soldermask Bottom")
		(17 "Dwgs.User" user "User.Drawings")
		(19 "Cmts.User" user "User.Comments")
		(21 "Eco1.User" user "User.Eco1")
		(23 "Eco2.User" user "User.Eco2")
		(25 "Edge.Cuts" user "Board Geometry/Outline")
		(27 "Margin" user)
		(31 "F.CrtYd" user "Package Geometry/Place Bound Top")
		(29 "B.CrtYd" user "Package Geometry/Place Bound Bottom")
		(35 "F.Fab" user "Ref Des/Assembly Top")
		(33 "B.Fab" user "Ref Des/Assembly Bottom")
	)
	(footprint ""
		(layer "B.Cu")
		(at 137.795 -16.256)
		(property "Reference" "R230"
			(at -1.397 1.43637 0)
			(unlocked yes)
			(layer "B.SilkS")
			(effects
				(font
					(size 0.7874 0.5842)
					(thickness 0.1524)
				)
				(justify mirror)
			)
		)
		(property "Value" "VAL*"
			(at -0.02032 2.13233 0)
			(unlocked yes)
			(layer "B.Fab")
			(hide yes)
			(effects
				(font
					(size 0.7874 0.5842)
					(thickness 0.1524)
				)
				(justify mirror)
			)
		)
		(property "Tolerance" "TOL*"
			(at -0.044704 3.05435 0)
			(unlocked yes)
			(layer "Cmts.User")
			(hide yes)
			(effects
				(font
					(size 0.7874 0.5842)
					(thickness 0.1524)
				)
				(justify mirror)
			)
		)
		(property "User Part Number" "PARTNUM*"
			(at -0.02032 4.024884 0)
			(unlocked yes)
			(layer "Cmts.User")
			(hide yes)
			(effects
				(font
					(size 0.7874 0.5842)
					(thickness 0.1524)
				)
				(justify mirror)
			)
		)
		(property "Device Type" "RESISTOR-G155-100R0-J0,0OHM,-"
			(at -0.008382 1.210564 0)
			(unlocked yes)
			(layer "B.Fab")
			(hide yes)
			(effects
				(font
					(size 0.7874 0.5842)
					(thickness 0.1524)
				)
				(justify mirror)
			)
		)
		(duplicate_pad_numbers_are_jumpers no)
		(fp_line
			(start -1.143 -0.5588)
			(end 1.143 -0.5588)
			(stroke
				(width 0.1)
				(type default)
			)
			(layer "B.SilkS")
		)
		(fp_line
			(start -1.143 0.5588)
			(end -1.143 -0.5588)
			(stroke
				(width 0.1)
				(type default)
			)
			(layer "B.SilkS")
		)
		(fp_line
			(start 1.143 -0.5588)
			(end 1.143 0.5588)
			(stroke
				(width 0.1)
				(type default)
			)
			(layer "B.SilkS")
		)
		(fp_line
			(start 1.143 0.5588)
			(end -1.143 0.5588)
			(stroke
				(width 0.1)
				(type default)
			)
			(layer "B.SilkS")
		)
		(fp_rect
			(start 1.143 -0.5588)
			(end -1.143 0.5588)
			(stroke
				(width 0)
				(type default)
			)
			(fill no)
			(layer "B.CrtYd")
		)
		(fp_line
			(start -0.508 -0.3048)
			(end 0.508 -0.3048)
			(stroke
				(width 0.1)
				(type default)
			)
			(layer "B.Fab")
		)
		(fp_line
			(start -0.508 0.3048)
			(end -0.508 -0.3048)
			(stroke
				(width 0.1)
				(type default)
			)
			(layer "B.Fab")
		)
		(fp_line
			(start 0.508 -0.3048)
			(end 0.508 0.3048)
			(stroke
				(width 0.1)
				(type default)
			)
			(layer "B.Fab")
		)
		(fp_line
			(start 0.508 0.3048)
			(end -0.508 0.3048)
			(stroke
				(width 0.1)
				(type default)
			)
			(layer "B.Fab")
		)
		(pad "1" smd rect
			(at 0.5334 0 180)
			(size 0.7112 0.6096)
			(layers "B.Cu" "B.Mask" "B.Paste")
			(net "UNNAMED_515_CAPACITOR_I138_1")
		)
		(pad "2" smd rect
			(at -0.5334 0 180)
			(size 0.7112 0.6096)
			(layers "B.Cu" "B.Mask" "B.Paste")
			(net "FPGA_CFG_INIT_N")
		)
		(zone
			(layer "B.Cu")
			(hatch none 0.5)
			(connect_pads
				(clearance 0)
			)
			(min_thickness 0.25)
			(keepout
				(tracks allowed)
				(vias not_allowed)
				(pads allowed)
				(copperpour not_allowed)
				(footprints allowed)
			)
			(placement
				(enabled no)
				(sheetname "")
			)
			(fill
				(thermal_gap 0.5)
				(thermal_bridge_width 0.5)
				(island_removal_mode 0)
			)
			(polygon
				(pts
					(xy 137.8712 -16.5608) (xy 137.7188 -16.5608) (xy 137.7188 -15.9512) (xy 137.8712 -15.9512)
				)
			)
		)
	)
	(footprint ""
		(layer "B.Cu")
		(at 88.519 -84.455 180)
		(property "Reference" "R192"
			(at -0.254 5.54863 0)
			(unlocked yes)
			(layer "B.SilkS")
			(effects
				(font
					(size 0.7874 0.5842)
					(thickness 0.1524)
				)
				(justify mirror)
			)
		)
		(property "Value" "VAL*"
			(at -0.02032 2.13233 180)
			(unlocked yes)
			(layer "B.Fab")
			(hide yes)
			(effects
				(font
					(size 0.7874 0.5842)
					(thickness 0.1524)
				)
				(justify mirror)
			)
		)
		(property "Tolerance" "TOL*"
			(at -0.044704 3.05435 180)
			(unlocked yes)
			(layer "Cmts.User")
			(hide yes)
			(effects
				(font
					(size 0.7874 0.5842)
					(thickness 0.1524)
				)
				(justify mirror)
			)
		)
		(property "User Part Number" "PARTNUM*"
			(at -0.02032 4.024884 180)
			(unlocked yes)
			(layer "Cmts.User")
			(hide yes)
			(effects
				(font
					(size 0.7874 0.5842)
					(thickness 0.1524)
				)
				(justify mirror)
			)
		)
		(property "Device Type" "RESISTOR-G155-14701-01,4.7KOHMA"
			(at -0.008382 1.210564 180)
			(unlocked yes)
			(layer "B.Fab")
			(hide yes)
			(effects
				(font
					(size 0.7874 0.5842)
					(thickness 0.1524)
				)
				(justify mirror)
			)
		)
		(duplicate_pad_numbers_are_jumpers no)
		(fp_line
			(start 1.143 0.5588)
			(end -1.143 0.5588)
			(stroke
				(width 0.1)
				(type default)
			)
			(layer "B.SilkS")
		)
		(fp_line
			(start 1.143 -0.5588)
			(end 1.143 0.5588)
			(stroke
				(width 0.1)
				(type default)
			)
			(layer "B.SilkS")
		)
		(fp_line
			(start -1.143 0.5588)
			(end -1.143 -0.5588)
			(stroke
				(width 0.1)
				(type default)
			)
			(layer "B.SilkS")
		)
		(fp_line
			(start -1.143 -0.5588)
			(end 1.143 -0.5588)
			(stroke
				(width 0.1)
				(type default)
			)
			(layer "B.SilkS")
		)
		(fp_rect
			(start 1.143 -0.5588)
			(end -1.143 0.5588)
			(stroke
				(width 0)
				(type default)
			)
			(fill no)
			(layer "B.CrtYd")
		)
		(fp_line
			(start 0.508 0.3048)
			(end -0.508 0.3048)
			(stroke
				(width 0.1)
				(type default)
			)
			(layer "B.Fab")
		)
		(fp_line
			(start 0.508 -0.3048)
			(end 0.508 0.3048)
			(stroke
				(width 0.1)
				(type default)
			)
			(layer "B.Fab")
		)
		(fp_line
			(start -0.508 0.3048)
			(end -0.508 -0.3048)
			(stroke
				(width 0.1)
				(type default)
			)
			(layer "B.Fab")
		)
		(fp_line
			(start -0.508 -0.3048)
			(end 0.508 -0.3048)
			(stroke
				(width 0.1)
				(type default)
			)
			(layer "B.Fab")
		)
		(pad "1" smd rect
			(at 0.5334 0)
			(size 0.7112 0.6096)
			(layers "B.Cu" "B.Mask" "B.Paste")
			(net "FLASH_CLK")
		)
		(pad "2" smd rect
			(at -0.5334 0)
			(size 0.7112 0.6096)
			(layers "B.Cu" "B.Mask" "B.Paste")
			(net "SG")
		)
		(zone
			(layer "B.Cu")
			(hatch none 0.5)
			(connect_pads
				(clearance 0)
			)
			(min_thickness 0.25)
			(keepout
				(tracks allowed)
				(vias not_allowed)
				(pads allowed)
				(copperpour not_allowed)
				(footprints allowed)
			)
			(placement
				(enabled no)
				(sheetname "")
			)
			(fill
				(thermal_gap 0.5)
				(thermal_bridge_width 0.5)
				(island_removal_mode 0)
			)
			(polygon
				(pts
					(xy 88.4428 -84.1502) (xy 88.5952 -84.1502) (xy 88.5952 -84.7598) (xy 88.4428 -84.7598)
				)
			)
		)
	)
)
